# Lightning_M.2_EQL.xlsx — PCIe CLK (si-constraints)
| SPEC |  |  |  |
| Length match | 5 mil |  |  |
| NET | L1 | L1 < 4 inch | Length match <1 mil |
| D85_PCIE_A_REFCLK_P | 775.61 | OK | OK |
| D85_PCIE_A_REFCLK_N | 776.54 | OK |  |
| D85_PCIE_B_REFCLK_P | 966.45 | OK | OK |
| D85_PCIE_B_REFCLK_N | 966.59 | OK |  |
